(kicad_pcb
	(version 20260206)
	(generator "pcbnew")
	(generator_version "10.0")
	(general
		(thickness 1.6)
		(legacy_teardrops no)
	)
	(paper "A4")
	(title_block
		(title "dpb — 14545-sa.0730WZS0815.brd")
		(comment 1 "Honey Badger (Wiwynn) / footprints 590-595 of 1066")
	)
	(layers
		(0 "F.Cu" signal "TOP")
		(4 "In1.Cu" signal "L2GND")
		(6 "In2.Cu" signal "L3")
		(8 "In3.Cu" signal "L4VCC")
		(10 "In4.Cu" signal "L5VCC")
		(12 "In5.Cu" signal "L6")
		(14 "In6.Cu" signal "L7GND")
		(2 "B.Cu" signal "BOTTOM")
		(9 "F.Adhes" user "F.Adhesive")
		(11 "B.Adhes" user "B.Adhesive")
		(13 "F.Paste" user "Package Geometry/Pastemask Top")
		(15 "B.Paste" user "Package Geometry/Pastemask Bottom")
		(5 "F.SilkS" user "Ref Des/Silkscreen Top")
		(7 "B.SilkS" user "Ref Des/Silkscreen Bottom")
		(1 "F.Mask" user "Board Geometry/Soldermask Top")
		(3 "B.Mask" user "Board Geometry/Soldermask Bottom")
		(17 "Dwgs.User" user "User.Drawings")
		(19 "Cmts.User" user "User.Comments")
		(21 "Eco1.User" user "User.Eco1")
		(23 "Eco2.User" user "User.Eco2")
		(25 "Edge.Cuts" user "Board Geometry/Outline")
		(27 "Margin" user)
		(31 "F.CrtYd" user "Package Geometry/Place Bound Top")
		(29 "B.CrtYd" user "Package Geometry/Place Bound Bottom")
		(35 "F.Fab" user "Ref Des/Assembly Top")
		(33 "B.Fab" user "Ref Des/Assembly Bottom")
	)
	(footprint ""
		(layer "F.Cu")
		(at 193.166746 -290.5887 -90)
		(property "Reference" "Q6"
			(at 0 0 270)
			(layer "F.SilkS")
			(hide yes)
			(effects
				(font
					(size 1.27 1.27)
				)
			)
		)
		(property "Value" "2N7002DW-7F-GP"
			(at -2.3622 -8.2042 270)
			(unlocked yes)
			(layer "F.Fab")
			(hide yes)
			(effects
				(font
					(size 1.016 1.016)
					(thickness 0.1524)
				)
			)
		)
		(property "Device Type" "SOT-363H44"
			(at -2.3622 -10.1092 270)
			(unlocked yes)
			(layer "F.Fab")
			(hide yes)
			(effects
				(font
					(size 1.016 1.016)
					(thickness 0.1524)
				)
			)
		)
		(duplicate_pad_numbers_are_jumpers no)
		(fp_line
			(start -1.4478 1.7018)
			(end 1.4478 1.7018)
			(stroke
				(width 0.1524)
				(type default)
			)
			(layer "F.SilkS")
		)
		(fp_line
			(start 1.4478 1.7018)
			(end 1.4478 -1.7018)
			(stroke
				(width 0.1524)
				(type default)
			)
			(layer "F.SilkS")
		)
		(fp_line
			(start -1.27 1.524)
			(end -1.27 0.6604)
			(stroke
				(width 0.4826)
				(type default)
			)
			(layer "F.SilkS")
		)
		(fp_line
			(start -1.4478 -1.7018)
			(end -1.4478 1.7018)
			(stroke
				(width 0.1524)
				(type default)
			)
			(layer "F.SilkS")
		)
		(fp_line
			(start 1.4478 -1.7018)
			(end -1.4478 -1.7018)
			(stroke
				(width 0.1524)
				(type default)
			)
			(layer "F.SilkS")
		)
		(fp_poly
			(pts
				(xy -1.524 -1.778) (xy 1.524 -1.778) (xy 1.524 1.778) (xy -1.524 1.778)
			)
			(stroke
				(width 0)
				(type default)
			)
			(fill no)
			(layer "F.CrtYd")
		)
		(fp_poly
			(pts
				(xy -1.524 -1.778) (xy 1.524 -1.778) (xy 1.524 1.778) (xy -1.524 1.778)
			)
			(stroke
				(width 0)
				(type default)
			)
			(fill no)
			(layer "F.Fab")
		)
		(pad "1" smd rect
			(at -0.65024 0.9398 270)
			(size 0.4064 1.016)
			(layers "F.Cu" "F.Mask" "F.Paste")
			(net "GND")
		)
		(pad "2" smd rect
			(at 0 0.9398 270)
			(size 0.4064 1.016)
			(layers "F.Cu" "F.Mask" "F.Paste")
			(net "SW_PWR_R_HDD2")
		)
		(pad "3" smd rect
			(at 0.65024 0.9398 270)
			(size 0.4064 1.016)
			(layers "F.Cu" "F.Mask" "F.Paste")
			(net "SW_HDD2_P")
		)
		(pad "4" smd rect
			(at 0.65024 -0.9398 270)
			(size 0.4064 1.016)
			(layers "F.Cu" "F.Mask" "F.Paste")
			(net "GND")
		)
		(pad "5" smd rect
			(at 0 -0.9398 270)
			(size 0.4064 1.016)
			(layers "F.Cu" "F.Mask" "F.Paste")
			(net "SW_HDD2_G")
		)
		(pad "6" smd rect
			(at -0.65024 -0.9398 270)
			(size 0.4064 1.016)
			(layers "F.Cu" "F.Mask" "F.Paste")
			(net "SW_HDD2_R")
		)
	)
	(footprint ""
		(layer "F.Cu")
		(at 191.256412 -82.276696 -90)
		(property "Reference" "R164"
			(at 0 0 270)
			(layer "F.SilkS")
			(hide yes)
			(effects
				(font
					(size 1.27 1.27)
				)
			)
		)
		(property "Value" "1KR2F-3-GP"
			(at 0.064008 -3.993896 270)
			(unlocked yes)
			(layer "F.Fab")
			(hide yes)
			(effects
				(font
					(size 1.016 1.016)
					(thickness 0.1524)
				)
			)
		)
		(property "Device Type" "R402H16"
			(at 0.064008 -5.517896 270)
			(unlocked yes)
			(layer "F.Fab")
			(hide yes)
			(effects
				(font
					(size 1.016 1.016)
					(thickness 0.1524)
				)
			)
		)
		(duplicate_pad_numbers_are_jumpers no)
		(fp_line
			(start -0.508 -0.9398)
			(end -0.508 0.9398)
			(stroke
				(width 0.1524)
				(type default)
			)
			(layer "F.SilkS")
		)
		(fp_line
			(start 0.508 -0.9398)
			(end -0.508 -0.9398)
			(stroke
				(width 0.1524)
				(type default)
			)
			(layer "F.SilkS")
		)
		(fp_rect
			(start -0.508 0.9398)
			(end 0.508 -0.9398)
			(stroke
				(width 0)
				(type default)
			)
			(fill no)
			(layer "F.CrtYd")
		)
		(fp_rect
			(start -0.508 0.9398)
			(end 0.508 -0.9398)
			(stroke
				(width 0)
				(type default)
			)
			(fill no)
			(layer "F.Fab")
		)
		(pad "1" smd custom
			(at 0 -0.4445 270)
			(size 0.1397 0.1397)
			(layers "F.Cu" "F.Mask" "F.Paste")
			(net "P3V3")
			(options
				(clearance outline)
				(anchor circle)
			)
			(primitives
				(gr_poly
					(pts
						(arc
							(start -0.1778 -0.2794)
							(mid -0.249642 -0.249642)
							(end -0.2794 -0.1778)
						)
						(arc
							(start -0.2794 0.1778)
							(mid -0.249642 0.249642)
							(end -0.1778 0.2794)
						)
						(arc
							(start 0.1778 0.2794)
							(mid 0.249642 0.249642)
							(end 0.2794 0.1778)
						)
						(arc
							(start 0.2794 -0.1778)
							(mid 0.249642 -0.249642)
							(end 0.1778 -0.2794)
						)
					)
					(width 0)
					(fill yes)
				)
			)
		)
		(pad "2" smd custom
			(at 0 0.4445 270)
			(size 0.1397 0.1397)
			(layers "F.Cu" "F.Mask" "F.Paste")
			(net "SW_PWR_HDD4")
			(options
				(clearance outline)
				(anchor circle)
			)
			(primitives
				(gr_poly
					(pts
						(arc
							(start -0.1778 -0.2794)
							(mid -0.249642 -0.249642)
							(end -0.2794 -0.1778)
						)
						(arc
							(start -0.2794 0.1778)
							(mid -0.249642 0.249642)
							(end -0.1778 0.2794)
						)
						(arc
							(start 0.1778 0.2794)
							(mid 0.249642 0.249642)
							(end 0.2794 0.1778)
						)
						(arc
							(start 0.2794 -0.1778)
							(mid 0.249642 -0.249642)
							(end 0.1778 -0.2794)
						)
					)
					(width 0)
					(fill yes)
				)
			)
		)
	)
	(footprint ""
		(layer "F.Cu")
		(at 33.914334 -30.499558 180)
		(property "Reference" "PTC4"
			(at 0 0 180)
			(layer "F.SilkS")
			(hide yes)
			(effects
				(font
					(size 1.27 1.27)
				)
			)
		)
		(property "Value" "ST330U10VDM-2GP"
			(at 0 -9.6012 180)
			(unlocked yes)
			(layer "F.Fab")
			(hide yes)
			(effects
				(font
					(size 1.016 1.016)
					(thickness 0.1524)
				)
			)
		)
		(property "Device Type" "CT7343H150"
			(at 0 -11.1252 180)
			(unlocked yes)
			(layer "F.Fab")
			(hide yes)
			(effects
				(font
					(size 1.016 1.016)
					(thickness 0.1524)
				)
			)
		)
		(duplicate_pad_numbers_are_jumpers no)
		(fp_line
			(start 2.286 4.8768)
			(end -2.286 4.8768)
			(stroke
				(width 0.1524)
				(type default)
			)
			(layer "F.SilkS")
		)
		(fp_line
			(start 2.286 2.032)
			(end 2.286 4.8768)
			(stroke
				(width 0.1524)
				(type default)
			)
			(layer "F.SilkS")
		)
		(fp_line
			(start 2.286 -2.032)
			(end 2.286 -4.8768)
			(stroke
				(width 0.1524)
				(type default)
			)
			(layer "F.SilkS")
		)
		(fp_line
			(start 2.286 -4.8768)
			(end -2.286 -4.8768)
			(stroke
				(width 0.1524)
				(type default)
			)
			(layer "F.SilkS")
		)
		(fp_line
			(start 2.1082 -4.699)
			(end -2.1082 -4.699)
			(stroke
				(width 0.508)
				(type default)
			)
			(layer "F.SilkS")
		)
		(fp_line
			(start -2.286 4.8768)
			(end -2.286 2.032)
			(stroke
				(width 0.1524)
				(type default)
			)
			(layer "F.SilkS")
		)
		(fp_line
			(start -2.286 -4.8768)
			(end -2.286 -2.032)
			(stroke
				(width 0.1524)
				(type default)
			)
			(layer "F.SilkS")
		)
		(fp_rect
			(start -2.1463 3.6449)
			(end 2.1463 -3.6449)
			(stroke
				(width 0)
				(type default)
			)
			(fill no)
			(layer "F.CrtYd")
		)
		(fp_poly
			(pts
				(xy -2.54 4.953) (xy -2.54 4.2926) (xy -3.81 4.2926) (xy -3.81 -4.2926) (xy -2.54 -4.2926) (xy -2.54 -4.953)
				(xy 2.54 -4.953) (xy 2.54 -4.2926) (xy 3.81 -4.2926) (xy 3.81 -1.6256) (xy 2.1463 -1.6256) (xy 2.1463 -3.6449)
				(xy -2.1463 -3.6449) (xy -2.1463 3.6449) (xy 2.1463 3.6449) (xy 2.1463 -1.6129) (xy 3.81 -1.6129)
				(xy 3.81 4.2926) (xy 2.54 4.2926) (xy 2.54 4.953)
			)
			(stroke
				(width 0)
				(type default)
			)
			(fill no)
			(layer "F.CrtYd")
		)
		(fp_rect
			(start 2.54 4.2926)
			(end 3.81 -4.2926)
			(stroke
				(width 0)
				(type default)
			)
			(fill no)
			(layer "F.Fab")
		)
		(fp_rect
			(start -2.54 4.953)
			(end 2.54 -4.953)
			(stroke
				(width 0)
				(type default)
			)
			(fill no)
			(layer "F.Fab")
		)
		(fp_rect
			(start -3.81 4.2926)
			(end -2.54 -4.2926)
			(stroke
				(width 0)
				(type default)
			)
			(fill no)
			(layer "F.Fab")
		)
		(pad "1" smd rect
			(at 0 -3.1496 180)
			(size 2.413 2.286)
			(layers "F.Cu" "F.Mask" "F.Paste")
			(net "P5VB")
		)
		(pad "2" smd rect
			(at 0 3.1496 180)
			(size 2.413 2.286)
			(layers "F.Cu" "F.Mask" "F.Paste")
			(net "GND")
		)
		(zone
			(layer "F.Cu")
			(hatch none 0.5)
			(connect_pads
				(clearance 0)
			)
			(min_thickness 0.25)
			(keepout
				(tracks allowed)
				(vias not_allowed)
				(pads allowed)
				(copperpour not_allowed)
				(footprints allowed)
			)
			(placement
				(enabled no)
				(sheetname "")
			)
			(fill
				(thermal_gap 0.5)
				(thermal_bridge_width 0.5)
				(island_removal_mode 0)
			)
			(polygon
				(pts
					(xy 32.403034 -28.810458) (xy 32.403034 -25.902158) (xy 35.425634 -25.902158) (xy 35.425634 -28.797758)
					(xy 35.425634 -29.127958) (xy 32.403034 -29.127958)
				)
			)
		)
		(zone
			(layer "F.Cu")
			(hatch none 0.5)
			(connect_pads
				(clearance 0)
			)
			(min_thickness 0.25)
			(keepout
				(tracks allowed)
				(vias not_allowed)
				(pads allowed)
				(copperpour not_allowed)
				(footprints allowed)
			)
			(placement
				(enabled no)
				(sheetname "")
			)
			(fill
				(thermal_gap 0.5)
				(thermal_bridge_width 0.5)
				(island_removal_mode 0)
			)
			(polygon
				(pts
					(xy 35.425634 -35.096958) (xy 32.403034 -35.096958) (xy 32.403034 -32.201358) (xy 32.403034 -31.871158)
					(xy 35.425634 -31.871158) (xy 35.425634 -32.201358)
				)
			)
		)
	)
	(footprint ""
		(layer "F.Cu")
		(at 81.5594 -24.1046 90)
		(property "Reference" "Q74"
			(at 0 0 90)
			(layer "F.SilkS")
			(hide yes)
			(effects
				(font
					(size 1.27 1.27)
				)
			)
		)
		(property "Value" "2N7002DW-7F-GP"
			(at -2.3622 -8.2042 90)
			(unlocked yes)
			(layer "F.Fab")
			(hide yes)
			(effects
				(font
					(size 1.016 1.016)
					(thickness 0.1524)
				)
			)
		)
		(property "Device Type" "SOT-363H44"
			(at -2.3622 -10.1092 90)
			(unlocked yes)
			(layer "F.Fab")
			(hide yes)
			(effects
				(font
					(size 1.016 1.016)
					(thickness 0.1524)
				)
			)
		)
		(duplicate_pad_numbers_are_jumpers no)
		(fp_line
			(start 1.4478 -1.7018)
			(end -1.4478 -1.7018)
			(stroke
				(width 0.1524)
				(type default)
			)
			(layer "F.SilkS")
		)
		(fp_line
			(start -1.4478 -1.7018)
			(end -1.4478 1.7018)
			(stroke
				(width 0.1524)
				(type default)
			)
			(layer "F.SilkS")
		)
		(fp_line
			(start -1.27 1.524)
			(end -1.27 0.6604)
			(stroke
				(width 0.4826)
				(type default)
			)
			(layer "F.SilkS")
		)
		(fp_line
			(start 1.4478 1.7018)
			(end 1.4478 -1.7018)
			(stroke
				(width 0.1524)
				(type default)
			)
			(layer "F.SilkS")
		)
		(fp_line
			(start -1.4478 1.7018)
			(end 1.4478 1.7018)
			(stroke
				(width 0.1524)
				(type default)
			)
			(layer "F.SilkS")
		)
		(fp_poly
			(pts
				(xy -1.524 -1.778) (xy 1.524 -1.778) (xy 1.524 1.778) (xy -1.524 1.778)
			)
			(stroke
				(width 0)
				(type default)
			)
			(fill no)
			(layer "F.CrtYd")
		)
		(fp_poly
			(pts
				(xy -1.524 -1.778) (xy 1.524 -1.778) (xy 1.524 1.778) (xy -1.524 1.778)
			)
			(stroke
				(width 0)
				(type default)
			)
			(fill no)
			(layer "F.Fab")
		)
		(pad "1" smd rect
			(at -0.65024 0.9398 90)
			(size 0.4064 1.016)
			(layers "F.Cu" "F.Mask" "F.Paste")
			(net "P3V3_HDD14_LED")
		)
		(pad "2" smd rect
			(at 0 0.9398 90)
			(size 0.4064 1.016)
			(layers "F.Cu" "F.Mask" "F.Paste")
			(net "HDD14_LED_G")
		)
		(pad "3" smd rect
			(at 0.65024 0.9398 90)
			(size 0.4064 1.016)
			(layers "F.Cu" "F.Mask" "F.Paste")
			(net "P5VC")
		)
		(pad "4" smd rect
			(at 0.65024 -0.9398 90)
			(size 0.4064 1.016)
			(layers "F.Cu" "F.Mask" "F.Paste")
			(net "P5VC_HDD14_LED")
		)
		(pad "5" smd rect
			(at 0 -0.9398 90)
			(size 0.4064 1.016)
			(layers "F.Cu" "F.Mask" "F.Paste")
			(net "HDD14_LED_G")
		)
		(pad "6" smd rect
			(at -0.65024 -0.9398 90)
			(size 0.4064 1.016)
			(layers "F.Cu" "F.Mask" "F.Paste")
			(net "P3V3")
		)
	)
	(footprint ""
		(layer "F.Cu")
		(at 207.4926 -170.2054 -90)
		(property "Reference" "Q52"
			(at 0 0 270)
			(layer "F.SilkS")
			(hide yes)
			(effects
				(font
					(size 1.27 1.27)
				)
			)
		)
		(property "Value" "2N7002DW-7F-GP"
			(at -2.3622 -8.2042 270)
			(unlocked yes)
			(layer "F.Fab")
			(hide yes)
			(effects
				(font
					(size 1.016 1.016)
					(thickness 0.1524)
				)
			)
		)
		(property "Device Type" "SOT-363H44"
			(at -2.3622 -10.1092 270)
			(unlocked yes)
			(layer "F.Fab")
			(hide yes)
			(effects
				(font
					(size 1.016 1.016)
					(thickness 0.1524)
				)
			)
		)
		(duplicate_pad_numbers_are_jumpers no)
		(fp_line
			(start -1.4478 1.7018)
			(end 1.4478 1.7018)
			(stroke
				(width 0.1524)
				(type default)
			)
			(layer "F.SilkS")
		)
		(fp_line
			(start 1.4478 1.7018)
			(end 1.4478 -1.7018)
			(stroke
				(width 0.1524)
				(type default)
			)
			(layer "F.SilkS")
		)
		(fp_line
			(start -1.27 1.524)
			(end -1.27 0.6604)
			(stroke
				(width 0.4826)
				(type default)
			)
			(layer "F.SilkS")
		)
		(fp_line
			(start -1.4478 -1.7018)
			(end -1.4478 1.7018)
			(stroke
				(width 0.1524)
				(type default)
			)
			(layer "F.SilkS")
		)
		(fp_line
			(start 1.4478 -1.7018)
			(end -1.4478 -1.7018)
			(stroke
				(width 0.1524)
				(type default)
			)
			(layer "F.SilkS")
		)
		(fp_poly
			(pts
				(xy -1.524 -1.778) (xy 1.524 -1.778) (xy 1.524 1.778) (xy -1.524 1.778)
			)
			(stroke
				(width 0)
				(type default)
			)
			(fill no)
			(layer "F.CrtYd")
		)
		(fp_poly
			(pts
				(xy -1.524 -1.778) (xy 1.524 -1.778) (xy 1.524 1.778) (xy -1.524 1.778)
			)
			(stroke
				(width 0)
				(type default)
			)
			(fill no)
			(layer "F.Fab")
		)
		(pad "1" smd rect
			(at -0.65024 0.9398 270)
			(size 0.4064 1.016)
			(layers "F.Cu" "F.Mask" "F.Paste")
			(net "P3V3_HDD3_LED")
		)
		(pad "2" smd rect
			(at 0 0.9398 270)
			(size 0.4064 1.016)
			(layers "F.Cu" "F.Mask" "F.Paste")
			(net "HDD3_LED_G")
		)
		(pad "3" smd rect
			(at 0.65024 0.9398 270)
			(size 0.4064 1.016)
			(layers "F.Cu" "F.Mask" "F.Paste")
			(net "P5VA")
		)
		(pad "4" smd rect
			(at 0.65024 -0.9398 270)
			(size 0.4064 1.016)
			(layers "F.Cu" "F.Mask" "F.Paste")
			(net "P5VA_HDD3_LED")
		)
		(pad "5" smd rect
			(at 0 -0.9398 270)
			(size 0.4064 1.016)
			(layers "F.Cu" "F.Mask" "F.Paste")
			(net "HDD3_LED_G")
		)
		(pad "6" smd rect
			(at -0.65024 -0.9398 270)
			(size 0.4064 1.016)
			(layers "F.Cu" "F.Mask" "F.Paste")
			(net "P3V3")
		)
	)
	(footprint ""
		(layer "F.Cu")
		(at 18.541746 -476.7707)
		(property "Reference" "PC38"
			(at 0 0 0)
			(layer "F.SilkS")
			(hide yes)
			(effects
				(font
					(size 1.27 1.27)
				)
			)
		)
		(property "Value" "SC10U16V6KX-2GP"
			(at -0.0762 -5.1308 0)
			(unlocked yes)
			(layer "F.Fab")
			(hide yes)
			(effects
				(font
					(size 1.016 1.016)
					(thickness 0.1524)
				)
			)
		)
		(property "Device Type" "C1206H71"
			(at -0.127 -6.6548 0)
			(unlocked yes)
			(layer "F.Fab")
			(hide yes)
			(effects
				(font
					(size 1.016 1.016)
					(thickness 0.1524)
				)
			)
		)
		(duplicate_pad_numbers_are_jumpers no)
		(fp_line
			(start -1.016 -2.2352)
			(end 1.016 -2.2352)
			(stroke
				(width 0.1524)
				(type default)
			)
			(layer "F.SilkS")
		)
		(fp_line
			(start -1.016 -0.8382)
			(end -1.016 -2.2352)
			(stroke
				(width 0.1524)
				(type default)
			)
			(layer "F.SilkS")
		)
		(fp_line
			(start -1.016 2.2352)
			(end -1.016 0.8382)
			(stroke
				(width 0.1524)
				(type default)
			)
			(layer "F.SilkS")
		)
		(fp_line
			(start 1.016 -2.2352)
			(end 1.016 -0.8382)
			(stroke
				(width 0.1524)
				(type default)
			)
			(layer "F.SilkS")
		)
		(fp_line
			(start 1.016 0.8382)
			(end 1.016 2.2352)
			(stroke
				(width 0.1524)
				(type default)
			)
			(layer "F.SilkS")
		)
		(fp_line
			(start 1.016 2.2352)
			(end -1.016 2.2352)
			(stroke
				(width 0.1524)
				(type default)
			)
			(layer "F.SilkS")
		)
		(fp_rect
			(start -1.0922 2.3114)
			(end 1.0922 -2.3114)
			(stroke
				(width 0)
				(type default)
			)
			(fill no)
			(layer "F.CrtYd")
		)
		(fp_poly
			(pts
				(xy 1.0922 -2.3114) (xy 1.0922 2.3114) (xy -1.0922 2.3114) (xy -1.0922 -2.3114)
			)
			(stroke
				(width 0)
				(type default)
			)
			(fill no)
			(layer "F.Fab")
		)
		(pad "1" smd rect
			(at 0 -1.397)
			(size 1.651 1.27)
			(layers "F.Cu" "F.Mask" "F.Paste")
			(net "P5VC")
		)
		(pad "2" smd rect
			(at 0 1.397)
			(size 1.651 1.27)
			(layers "F.Cu" "F.Mask" "F.Paste")
			(net "GND")
		)
	)
)
